(kicad_pcb
	(version 20260206)
	(generator "pcbnew")
	(generator_version "10.0")
	(general
		(thickness 1.6)
		(legacy_teardrops no)
	)
	(paper "A4")
	(title_block
		(title "04192023_DAF0TMB3IC0_F0TG_MB_C_brd_V02_OCP.brd")
		(comment 1 "Grand Teton / footprints 2013-2017 of 8354")
	)
	(layers
		(0 "F.Cu" signal "TOP")
		(4 "In1.Cu" signal "GND")
		(6 "In2.Cu" signal "IN1")
		(8 "In3.Cu" signal "GND1")
		(10 "In4.Cu" signal "IN2")
		(12 "In5.Cu" signal "GND2")
		(14 "In6.Cu" signal "IN3")
		(16 "In7.Cu" signal "GND3")
		(18 "In8.Cu" signal "VCC")
		(20 "In9.Cu" signal "VCC1")
		(22 "In10.Cu" signal "GND4")
		(24 "In11.Cu" signal "IN4")
		(26 "In12.Cu" signal "GND5")
		(28 "In13.Cu" signal "IN5")
		(30 "In14.Cu" signal "GND6")
		(32 "In15.Cu" signal "IN6")
		(34 "In16.Cu" signal "GND7")
		(2 "B.Cu" signal "BOTTOM")
		(9 "F.Adhes" user "F.Adhesive")
		(11 "B.Adhes" user "B.Adhesive")
		(13 "F.Paste" user "Package Geometry/Pastemask Top")
		(15 "B.Paste" user "Package Geometry/Pastemask Bottom")
		(5 "F.SilkS" user "Ref Des/Silkscreen Top")
		(7 "B.SilkS" user "Ref Des/Silkscreen Bottom")
		(1 "F.Mask" user "Board Geometry/Soldermask Top")
		(3 "B.Mask" user "Board Geometry/Soldermask Bottom")
		(17 "Dwgs.User" user "User.Drawings")
		(19 "Cmts.User" user "User.Comments")
		(21 "Eco1.User" user "User.Eco1")
		(23 "Eco2.User" user "User.Eco2")
		(25 "Edge.Cuts" user "Board Geometry/Outline")
		(27 "Margin" user)
		(31 "F.CrtYd" user "Package Geometry/Place Bound Top")
		(29 "B.CrtYd" user "Package Geometry/Place Bound Bottom")
		(35 "F.Fab" user "Ref Des/Assembly Top")
		(33 "B.Fab" user "Ref Des/Assembly Bottom")
	)
	(footprint ""
		(layer "F.Cu")
		(at 295.09085 -369.375436 180)
		(property "Reference" "PR55"
			(at 0 0 180)
			(layer "F.SilkS")
			(hide yes)
			(effects
				(font
					(size 1.27 1.27)
				)
			)
		)
		(property "Value" ""
			(at 0 0 180)
			(layer "F.Fab")
			(effects
				(font
					(size 1.27 1.27)
				)
			)
		)
		(duplicate_pad_numbers_are_jumpers no)
		(fp_line
			(start 0.7874 0.4064)
			(end -0.7874 0.4064)
			(stroke
				(width 0.1524)
				(type default)
			)
			(layer "F.SilkS")
		)
		(fp_line
			(start 0.7874 -0.4064)
			(end 0.7874 0.4064)
			(stroke
				(width 0.1524)
				(type default)
			)
			(layer "F.SilkS")
		)
		(fp_line
			(start -0.7874 0.4064)
			(end -0.7874 -0.4064)
			(stroke
				(width 0.1524)
				(type default)
			)
			(layer "F.SilkS")
		)
		(fp_line
			(start -0.7874 -0.4064)
			(end 0.7874 -0.4064)
			(stroke
				(width 0.1524)
				(type default)
			)
			(layer "F.SilkS")
		)
		(fp_line
			(start 0.67945 0.3048)
			(end 0.120396 0.3048)
			(stroke
				(width 0.1)
				(type default)
			)
			(layer "F.Fab")
		)
		(fp_line
			(start 0.67945 -0.3048)
			(end 0.67945 0.3048)
			(stroke
				(width 0.1)
				(type default)
			)
			(layer "F.Fab")
		)
		(fp_line
			(start 0.12065 -0.2794)
			(end 0.12065 -0.3048)
			(stroke
				(width 0.1)
				(type default)
			)
			(layer "F.Fab")
		)
		(fp_line
			(start 0.12065 -0.3048)
			(end 0.67945 -0.3048)
			(stroke
				(width 0.1)
				(type default)
			)
			(layer "F.Fab")
		)
		(fp_line
			(start 0.120396 0.3048)
			(end 0.120396 0.2794)
			(stroke
				(width 0.1)
				(type default)
			)
			(layer "F.Fab")
		)
		(fp_line
			(start 0.120396 0.2794)
			(end -0.12065 0.2794)
			(stroke
				(width 0.1)
				(type default)
			)
			(layer "F.Fab")
		)
		(fp_line
			(start -0.12065 0.3048)
			(end -0.67945 0.3048)
			(stroke
				(width 0.1)
				(type default)
			)
			(layer "F.Fab")
		)
		(fp_line
			(start -0.12065 0.2794)
			(end -0.12065 0.3048)
			(stroke
				(width 0.1)
				(type default)
			)
			(layer "F.Fab")
		)
		(fp_line
			(start -0.12065 -0.2794)
			(end 0.12065 -0.2794)
			(stroke
				(width 0.1)
				(type default)
			)
			(layer "F.Fab")
		)
		(fp_line
			(start -0.12065 -0.305054)
			(end -0.12065 -0.2794)
			(stroke
				(width 0.1)
				(type default)
			)
			(layer "F.Fab")
		)
		(fp_line
			(start -0.67945 0.3048)
			(end -0.67945 -0.305054)
			(stroke
				(width 0.1)
				(type default)
			)
			(layer "F.Fab")
		)
		(fp_line
			(start -0.67945 -0.305054)
			(end -0.12065 -0.305054)
			(stroke
				(width 0.1)
				(type default)
			)
			(layer "F.Fab")
		)
		(pad "1" smd circle
			(at -0.40005 0 180)
			(size 0 0)
			(layers "F.Cu" "F.Mask" "F.Paste")
			(net "P3V3_AUX")
		)
		(pad "2" smd circle
			(at 0.40005 0 180)
			(size 0 0)
			(layers "F.Cu" "F.Mask" "F.Paste")
			(net "PVDDIO_P0_EN_G")
		)
	)
	(footprint ""
		(layer "F.Cu")
		(at 409.824936 -170.328082 -90)
		(property "Reference" "PR503"
			(at 0 0 270)
			(layer "F.SilkS")
			(hide yes)
			(effects
				(font
					(size 1.27 1.27)
				)
			)
		)
		(property "Value" ""
			(at 0 0 270)
			(layer "F.Fab")
			(effects
				(font
					(size 1.27 1.27)
				)
			)
		)
		(duplicate_pad_numbers_are_jumpers no)
		(fp_line
			(start -0.7874 0.4064)
			(end -0.7874 -0.4064)
			(stroke
				(width 0.1524)
				(type default)
			)
			(layer "F.SilkS")
		)
		(fp_line
			(start 0.7874 0.4064)
			(end -0.7874 0.4064)
			(stroke
				(width 0.1524)
				(type default)
			)
			(layer "F.SilkS")
		)
		(fp_line
			(start -0.7874 -0.4064)
			(end 0.7874 -0.4064)
			(stroke
				(width 0.1524)
				(type default)
			)
			(layer "F.SilkS")
		)
		(fp_line
			(start 0.7874 -0.4064)
			(end 0.7874 0.4064)
			(stroke
				(width 0.1524)
				(type default)
			)
			(layer "F.SilkS")
		)
		(fp_line
			(start -0.67945 0.3048)
			(end -0.67945 -0.305054)
			(stroke
				(width 0.1)
				(type default)
			)
			(layer "F.Fab")
		)
		(fp_line
			(start -0.12065 0.3048)
			(end -0.67945 0.3048)
			(stroke
				(width 0.1)
				(type default)
			)
			(layer "F.Fab")
		)
		(fp_line
			(start 0.120396 0.3048)
			(end 0.120396 0.2794)
			(stroke
				(width 0.1)
				(type default)
			)
			(layer "F.Fab")
		)
		(fp_line
			(start 0.67945 0.3048)
			(end 0.120396 0.3048)
			(stroke
				(width 0.1)
				(type default)
			)
			(layer "F.Fab")
		)
		(fp_line
			(start -0.12065 0.2794)
			(end -0.12065 0.3048)
			(stroke
				(width 0.1)
				(type default)
			)
			(layer "F.Fab")
		)
		(fp_line
			(start 0.120396 0.2794)
			(end -0.12065 0.2794)
			(stroke
				(width 0.1)
				(type default)
			)
			(layer "F.Fab")
		)
		(fp_line
			(start -0.12065 -0.2794)
			(end 0.12065 -0.2794)
			(stroke
				(width 0.1)
				(type default)
			)
			(layer "F.Fab")
		)
		(fp_line
			(start 0.12065 -0.2794)
			(end 0.12065 -0.3048)
			(stroke
				(width 0.1)
				(type default)
			)
			(layer "F.Fab")
		)
		(fp_line
			(start 0.12065 -0.3048)
			(end 0.67945 -0.3048)
			(stroke
				(width 0.1)
				(type default)
			)
			(layer "F.Fab")
		)
		(fp_line
			(start 0.67945 -0.3048)
			(end 0.67945 0.3048)
			(stroke
				(width 0.1)
				(type default)
			)
			(layer "F.Fab")
		)
		(fp_line
			(start -0.67945 -0.305054)
			(end -0.12065 -0.305054)
			(stroke
				(width 0.1)
				(type default)
			)
			(layer "F.Fab")
		)
		(fp_line
			(start -0.12065 -0.305054)
			(end -0.12065 -0.2794)
			(stroke
				(width 0.1)
				(type default)
			)
			(layer "F.Fab")
		)
		(pad "1" smd circle
			(at -0.40005 0 270)
			(size 0 0)
			(layers "F.Cu" "F.Mask" "F.Paste")
			(net "SW_PVDDCR_SOC_P0_SW2_RC")
		)
		(pad "2" smd circle
			(at 0.40005 0 270)
			(size 0 0)
			(layers "F.Cu" "F.Mask" "F.Paste")
			(net "GND")
		)
	)
	(footprint ""
		(layer "F.Cu")
		(at 205.665832 -137.527792)
		(property "Reference" "R2528"
			(at 0 0 0)
			(layer "F.SilkS")
			(hide yes)
			(effects
				(font
					(size 1.27 1.27)
				)
			)
		)
		(property "Value" ""
			(at 0 0 0)
			(layer "F.Fab")
			(effects
				(font
					(size 1.27 1.27)
				)
			)
		)
		(duplicate_pad_numbers_are_jumpers no)
		(fp_line
			(start -0.7874 -0.4064)
			(end 0.7874 -0.4064)
			(stroke
				(width 0.1524)
				(type default)
			)
			(layer "F.SilkS")
		)
		(fp_line
			(start -0.7874 0.4064)
			(end -0.7874 -0.4064)
			(stroke
				(width 0.1524)
				(type default)
			)
			(layer "F.SilkS")
		)
		(fp_line
			(start 0.7874 -0.4064)
			(end 0.7874 0.4064)
			(stroke
				(width 0.1524)
				(type default)
			)
			(layer "F.SilkS")
		)
		(fp_line
			(start 0.7874 0.4064)
			(end -0.7874 0.4064)
			(stroke
				(width 0.1524)
				(type default)
			)
			(layer "F.SilkS")
		)
		(fp_line
			(start -0.67945 -0.305054)
			(end -0.12065 -0.305054)
			(stroke
				(width 0.1)
				(type default)
			)
			(layer "F.Fab")
		)
		(fp_line
			(start -0.67945 0.3048)
			(end -0.67945 -0.305054)
			(stroke
				(width 0.1)
				(type default)
			)
			(layer "F.Fab")
		)
		(fp_line
			(start -0.12065 -0.305054)
			(end -0.12065 -0.2794)
			(stroke
				(width 0.1)
				(type default)
			)
			(layer "F.Fab")
		)
		(fp_line
			(start -0.12065 -0.2794)
			(end 0.12065 -0.2794)
			(stroke
				(width 0.1)
				(type default)
			)
			(layer "F.Fab")
		)
		(fp_line
			(start -0.12065 0.2794)
			(end -0.12065 0.3048)
			(stroke
				(width 0.1)
				(type default)
			)
			(layer "F.Fab")
		)
		(fp_line
			(start -0.12065 0.3048)
			(end -0.67945 0.3048)
			(stroke
				(width 0.1)
				(type default)
			)
			(layer "F.Fab")
		)
		(fp_line
			(start 0.120396 0.2794)
			(end -0.12065 0.2794)
			(stroke
				(width 0.1)
				(type default)
			)
			(layer "F.Fab")
		)
		(fp_line
			(start 0.120396 0.3048)
			(end 0.120396 0.2794)
			(stroke
				(width 0.1)
				(type default)
			)
			(layer "F.Fab")
		)
		(fp_line
			(start 0.12065 -0.3048)
			(end 0.67945 -0.3048)
			(stroke
				(width 0.1)
				(type default)
			)
			(layer "F.Fab")
		)
		(fp_line
			(start 0.12065 -0.2794)
			(end 0.12065 -0.3048)
			(stroke
				(width 0.1)
				(type default)
			)
			(layer "F.Fab")
		)
		(fp_line
			(start 0.67945 -0.3048)
			(end 0.67945 0.3048)
			(stroke
				(width 0.1)
				(type default)
			)
			(layer "F.Fab")
		)
		(fp_line
			(start 0.67945 0.3048)
			(end 0.120396 0.3048)
			(stroke
				(width 0.1)
				(type default)
			)
			(layer "F.Fab")
		)
		(pad "1" smd circle
			(at -0.40005 0)
			(size 0 0)
			(layers "F.Cu" "F.Mask" "F.Paste")
			(net "P12V_AUX")
		)
		(pad "2" smd circle
			(at 0.40005 0)
			(size 0 0)
			(layers "F.Cu" "F.Mask" "F.Paste")
			(net "FM_P12V_HSC_EN_N")
		)
	)
	(footprint ""
		(layer "F.Cu")
		(at 121.539 -321.691 90)
		(property "Reference" "R8350"
			(at 0 0 90)
			(layer "F.SilkS")
			(hide yes)
			(effects
				(font
					(size 1.27 1.27)
				)
			)
		)
		(property "Value" ""
			(at 0 0 90)
			(layer "F.Fab")
			(effects
				(font
					(size 1.27 1.27)
				)
			)
		)
		(duplicate_pad_numbers_are_jumpers no)
		(fp_line
			(start -0.381 -0.4064)
			(end 0.4064 -0.4064)
			(stroke
				(width 0.1524)
				(type default)
			)
			(layer "F.SilkS")
		)
		(fp_line
			(start 0.7874 0)
			(end 0.7874 0.4064)
			(stroke
				(width 0.1524)
				(type default)
			)
			(layer "F.SilkS")
		)
		(fp_line
			(start 0.7874 0.4064)
			(end -0.7874 0.4064)
			(stroke
				(width 0.1524)
				(type default)
			)
			(layer "F.SilkS")
		)
		(fp_line
			(start -0.7874 0.4064)
			(end -0.7874 -0.0254)
			(stroke
				(width 0.1524)
				(type default)
			)
			(layer "F.SilkS")
		)
		(fp_line
			(start -0.12065 -0.305054)
			(end -0.12065 -0.2794)
			(stroke
				(width 0.1)
				(type default)
			)
			(layer "F.Fab")
		)
		(fp_line
			(start -0.67945 -0.305054)
			(end -0.12065 -0.305054)
			(stroke
				(width 0.1)
				(type default)
			)
			(layer "F.Fab")
		)
		(fp_line
			(start 0.67945 -0.3048)
			(end 0.67945 0.3048)
			(stroke
				(width 0.1)
				(type default)
			)
			(layer "F.Fab")
		)
		(fp_line
			(start 0.12065 -0.3048)
			(end 0.67945 -0.3048)
			(stroke
				(width 0.1)
				(type default)
			)
			(layer "F.Fab")
		)
		(fp_line
			(start 0.12065 -0.2794)
			(end 0.12065 -0.3048)
			(stroke
				(width 0.1)
				(type default)
			)
			(layer "F.Fab")
		)
		(fp_line
			(start -0.12065 -0.2794)
			(end 0.12065 -0.2794)
			(stroke
				(width 0.1)
				(type default)
			)
			(layer "F.Fab")
		)
		(fp_line
			(start 0.120396 0.2794)
			(end -0.12065 0.2794)
			(stroke
				(width 0.1)
				(type default)
			)
			(layer "F.Fab")
		)
		(fp_line
			(start -0.12065 0.2794)
			(end -0.12065 0.3048)
			(stroke
				(width 0.1)
				(type default)
			)
			(layer "F.Fab")
		)
		(fp_line
			(start 0.67945 0.3048)
			(end 0.120396 0.3048)
			(stroke
				(width 0.1)
				(type default)
			)
			(layer "F.Fab")
		)
		(fp_line
			(start 0.120396 0.3048)
			(end 0.120396 0.2794)
			(stroke
				(width 0.1)
				(type default)
			)
			(layer "F.Fab")
		)
		(fp_line
			(start -0.12065 0.3048)
			(end -0.67945 0.3048)
			(stroke
				(width 0.1)
				(type default)
			)
			(layer "F.Fab")
		)
		(fp_line
			(start -0.67945 0.3048)
			(end -0.67945 -0.305054)
			(stroke
				(width 0.1)
				(type default)
			)
			(layer "F.Fab")
		)
		(pad "1" smd circle
			(at -0.40005 0 90)
			(size 0 0)
			(layers "F.Cu" "F.Mask" "F.Paste")
			(net "CLK_100M_CPU1_CLK13_R_DP")
		)
		(pad "2" smd circle
			(at 0.40005 0 90)
			(size 0 0)
			(layers "F.Cu" "F.Mask" "F.Paste")
			(net "CLK_100M_CPU1_CLK13_DP")
		)
	)
	(footprint ""
		(layer "F.Cu")
		(at 304.419 -363.982 180)
		(property "Reference" "C8070"
			(at 0 0 180)
			(layer "F.SilkS")
			(hide yes)
			(effects
				(font
					(size 1.27 1.27)
				)
			)
		)
		(property "Value" ""
			(at 0 0 180)
			(layer "F.Fab")
			(effects
				(font
					(size 1.27 1.27)
				)
			)
		)
		(duplicate_pad_numbers_are_jumpers no)
		(fp_line
			(start 0.7874 0.4064)
			(end -0.7874 0.4064)
			(stroke
				(width 0.1524)
				(type default)
			)
			(layer "F.SilkS")
		)
		(fp_line
			(start 0.7874 -0.4064)
			(end 0.7874 0.4064)
			(stroke
				(width 0.1524)
				(type default)
			)
			(layer "F.SilkS")
		)
		(fp_line
			(start -0.7874 0.4064)
			(end -0.7874 -0.4064)
			(stroke
				(width 0.1524)
				(type default)
			)
			(layer "F.SilkS")
		)
		(fp_line
			(start -0.7874 -0.4064)
			(end 0.7874 -0.4064)
			(stroke
				(width 0.1524)
				(type default)
			)
			(layer "F.SilkS")
		)
		(fp_line
			(start 0.67945 0.3048)
			(end 0.120396 0.3048)
			(stroke
				(width 0.1)
				(type default)
			)
			(layer "F.Fab")
		)
		(fp_line
			(start 0.67945 -0.3048)
			(end 0.67945 0.3048)
			(stroke
				(width 0.1)
				(type default)
			)
			(layer "F.Fab")
		)
		(fp_line
			(start 0.12065 -0.2794)
			(end 0.12065 -0.3048)
			(stroke
				(width 0.1)
				(type default)
			)
			(layer "F.Fab")
		)
		(fp_line
			(start 0.12065 -0.3048)
			(end 0.67945 -0.3048)
			(stroke
				(width 0.1)
				(type default)
			)
			(layer "F.Fab")
		)
		(fp_line
			(start 0.120396 0.3048)
			(end 0.120396 0.2794)
			(stroke
				(width 0.1)
				(type default)
			)
			(layer "F.Fab")
		)
		(fp_line
			(start 0.120396 0.2794)
			(end -0.12065 0.2794)
			(stroke
				(width 0.1)
				(type default)
			)
			(layer "F.Fab")
		)
		(fp_line
			(start -0.12065 0.3048)
			(end -0.67945 0.3048)
			(stroke
				(width 0.1)
				(type default)
			)
			(layer "F.Fab")
		)
		(fp_line
			(start -0.12065 0.2794)
			(end -0.12065 0.3048)
			(stroke
				(width 0.1)
				(type default)
			)
			(layer "F.Fab")
		)
		(fp_line
			(start -0.12065 -0.2794)
			(end 0.12065 -0.2794)
			(stroke
				(width 0.1)
				(type default)
			)
			(layer "F.Fab")
		)
		(fp_line
			(start -0.12065 -0.305054)
			(end -0.12065 -0.2794)
			(stroke
				(width 0.1)
				(type default)
			)
			(layer "F.Fab")
		)
		(fp_line
			(start -0.67945 0.3048)
			(end -0.67945 -0.305054)
			(stroke
				(width 0.1)
				(type default)
			)
			(layer "F.Fab")
		)
		(fp_line
			(start -0.67945 -0.305054)
			(end -0.12065 -0.305054)
			(stroke
				(width 0.1)
				(type default)
			)
			(layer "F.Fab")
		)
		(pad "1" smd circle
			(at -0.40005 0 180)
			(size 0 0)
			(layers "F.Cu" "F.Mask" "F.Paste")
			(net "PWRGD_PVDDCR_CPU1_P0_R")
		)
		(pad "2" smd circle
			(at 0.40005 0 180)
			(size 0 0)
			(layers "F.Cu" "F.Mask" "F.Paste")
			(net "GND")
		)
	)
)
